(kicad_pcb
	(version 20260206)
	(generator "pcbnew")
	(generator_version "10.0")
	(general
		(thickness 1.6)
		(legacy_teardrops no)
	)
	(paper "A4")
	(title_block
		(title "01162023_DA0F0TEBIF0_F0T_Expander_BD_F_brd_V02_OCP.brd")
		(comment 1 "Grand Teton / footprints 2287-2293 of 9728")
	)
	(layers
		(0 "F.Cu" signal "TOP")
		(4 "In1.Cu" signal "GND")
		(6 "In2.Cu" signal "VCC")
		(8 "In3.Cu" signal "VCC1")
		(10 "In4.Cu" signal "GND1")
		(12 "In5.Cu" signal "IN1")
		(14 "In6.Cu" signal "GND2")
		(16 "In7.Cu" signal "IN2")
		(18 "In8.Cu" signal "GND3")
		(20 "In9.Cu" signal "IN3")
		(22 "In10.Cu" signal "GND4")
		(24 "In11.Cu" signal "IN4")
		(26 "In12.Cu" signal "GND5")
		(28 "In13.Cu" signal "IN5")
		(30 "In14.Cu" signal "GND6")
		(32 "In15.Cu" signal "IN6")
		(34 "In16.Cu" signal "GND7")
		(2 "B.Cu" signal "BOTTOM")
		(9 "F.Adhes" user "F.Adhesive")
		(11 "B.Adhes" user "B.Adhesive")
		(13 "F.Paste" user "Package Geometry/Pastemask Top")
		(15 "B.Paste" user "Package Geometry/Pastemask Bottom")
		(5 "F.SilkS" user "Ref Des/Silkscreen Top")
		(7 "B.SilkS" user "Ref Des/Silkscreen Bottom")
		(1 "F.Mask" user "Board Geometry/Soldermask Top")
		(3 "B.Mask" user "Board Geometry/Soldermask Bottom")
		(17 "Dwgs.User" user "User.Drawings")
		(19 "Cmts.User" user "User.Comments")
		(21 "Eco1.User" user "User.Eco1")
		(23 "Eco2.User" user "User.Eco2")
		(25 "Edge.Cuts" user "Board Geometry/Outline")
		(27 "Margin" user)
		(31 "F.CrtYd" user "Package Geometry/Place Bound Top")
		(29 "B.CrtYd" user "Package Geometry/Place Bound Bottom")
		(35 "F.Fab" user "Ref Des/Assembly Top")
		(33 "B.Fab" user "Ref Des/Assembly Bottom")
	)
	(footprint ""
		(layer "F.Cu")
		(at 256.02946 -195.573396 -90)
		(property "Reference" "R4300"
			(at 0 0 270)
			(layer "F.SilkS")
			(hide yes)
			(effects
				(font
					(size 1.27 1.27)
				)
			)
		)
		(property "Value" ""
			(at 0 0 270)
			(layer "F.Fab")
			(effects
				(font
					(size 1.27 1.27)
				)
			)
		)
		(duplicate_pad_numbers_are_jumpers no)
		(fp_line
			(start -0.7874 0.4064)
			(end -0.7874 -0.4064)
			(stroke
				(width 0.1524)
				(type default)
			)
			(layer "F.SilkS")
		)
		(fp_line
			(start 0.7874 0.4064)
			(end -0.7874 0.4064)
			(stroke
				(width 0.1524)
				(type default)
			)
			(layer "F.SilkS")
		)
		(fp_line
			(start -0.7874 -0.4064)
			(end 0.7874 -0.4064)
			(stroke
				(width 0.1524)
				(type default)
			)
			(layer "F.SilkS")
		)
		(fp_line
			(start 0.7874 -0.4064)
			(end 0.7874 0.4064)
			(stroke
				(width 0.1524)
				(type default)
			)
			(layer "F.SilkS")
		)
		(fp_line
			(start -0.67945 0.3048)
			(end -0.67945 -0.305054)
			(stroke
				(width 0.1)
				(type default)
			)
			(layer "F.Fab")
		)
		(fp_line
			(start -0.12065 0.3048)
			(end -0.67945 0.3048)
			(stroke
				(width 0.1)
				(type default)
			)
			(layer "F.Fab")
		)
		(fp_line
			(start 0.120396 0.3048)
			(end 0.120396 0.2794)
			(stroke
				(width 0.1)
				(type default)
			)
			(layer "F.Fab")
		)
		(fp_line
			(start 0.67945 0.3048)
			(end 0.120396 0.3048)
			(stroke
				(width 0.1)
				(type default)
			)
			(layer "F.Fab")
		)
		(fp_line
			(start -0.12065 0.2794)
			(end -0.12065 0.3048)
			(stroke
				(width 0.1)
				(type default)
			)
			(layer "F.Fab")
		)
		(fp_line
			(start 0.120396 0.2794)
			(end -0.12065 0.2794)
			(stroke
				(width 0.1)
				(type default)
			)
			(layer "F.Fab")
		)
		(fp_line
			(start -0.12065 -0.2794)
			(end 0.12065 -0.2794)
			(stroke
				(width 0.1)
				(type default)
			)
			(layer "F.Fab")
		)
		(fp_line
			(start 0.12065 -0.2794)
			(end 0.12065 -0.3048)
			(stroke
				(width 0.1)
				(type default)
			)
			(layer "F.Fab")
		)
		(fp_line
			(start 0.12065 -0.3048)
			(end 0.67945 -0.3048)
			(stroke
				(width 0.1)
				(type default)
			)
			(layer "F.Fab")
		)
		(fp_line
			(start 0.67945 -0.3048)
			(end 0.67945 0.3048)
			(stroke
				(width 0.1)
				(type default)
			)
			(layer "F.Fab")
		)
		(fp_line
			(start -0.67945 -0.305054)
			(end -0.12065 -0.305054)
			(stroke
				(width 0.1)
				(type default)
			)
			(layer "F.Fab")
		)
		(fp_line
			(start -0.12065 -0.305054)
			(end -0.12065 -0.2794)
			(stroke
				(width 0.1)
				(type default)
			)
			(layer "F.Fab")
		)
		(pad "1" smd circle
			(at -0.40005 0 270)
			(size 0 0)
			(layers "F.Cu" "F.Mask" "F.Paste")
			(net "JTAG_PLD_TMS")
		)
		(pad "2" smd circle
			(at 0.40005 0 270)
			(size 0 0)
			(layers "F.Cu" "F.Mask" "F.Paste")
			(net "JTAG_FPGA_TMS")
		)
	)
	(footprint ""
		(layer "F.Cu")
		(at 336.042 -177.927)
		(property "Reference" "R4725"
			(at 0 0 0)
			(layer "F.SilkS")
			(hide yes)
			(effects
				(font
					(size 1.27 1.27)
				)
			)
		)
		(property "Value" ""
			(at 0 0 0)
			(layer "F.Fab")
			(effects
				(font
					(size 1.27 1.27)
				)
			)
		)
		(duplicate_pad_numbers_are_jumpers no)
		(fp_line
			(start -0.7874 -0.4064)
			(end 0.7874 -0.4064)
			(stroke
				(width 0.1524)
				(type default)
			)
			(layer "F.SilkS")
		)
		(fp_line
			(start -0.7874 0.4064)
			(end -0.7874 -0.4064)
			(stroke
				(width 0.1524)
				(type default)
			)
			(layer "F.SilkS")
		)
		(fp_line
			(start 0.7874 -0.4064)
			(end 0.7874 0.4064)
			(stroke
				(width 0.1524)
				(type default)
			)
			(layer "F.SilkS")
		)
		(fp_line
			(start 0.7874 0.4064)
			(end -0.7874 0.4064)
			(stroke
				(width 0.1524)
				(type default)
			)
			(layer "F.SilkS")
		)
		(fp_line
			(start -0.67945 -0.305054)
			(end -0.12065 -0.305054)
			(stroke
				(width 0.1)
				(type default)
			)
			(layer "F.Fab")
		)
		(fp_line
			(start -0.67945 0.3048)
			(end -0.67945 -0.305054)
			(stroke
				(width 0.1)
				(type default)
			)
			(layer "F.Fab")
		)
		(fp_line
			(start -0.12065 -0.305054)
			(end -0.12065 -0.2794)
			(stroke
				(width 0.1)
				(type default)
			)
			(layer "F.Fab")
		)
		(fp_line
			(start -0.12065 -0.2794)
			(end 0.12065 -0.2794)
			(stroke
				(width 0.1)
				(type default)
			)
			(layer "F.Fab")
		)
		(fp_line
			(start -0.12065 0.2794)
			(end -0.12065 0.3048)
			(stroke
				(width 0.1)
				(type default)
			)
			(layer "F.Fab")
		)
		(fp_line
			(start -0.12065 0.3048)
			(end -0.67945 0.3048)
			(stroke
				(width 0.1)
				(type default)
			)
			(layer "F.Fab")
		)
		(fp_line
			(start 0.120396 0.2794)
			(end -0.12065 0.2794)
			(stroke
				(width 0.1)
				(type default)
			)
			(layer "F.Fab")
		)
		(fp_line
			(start 0.120396 0.3048)
			(end 0.120396 0.2794)
			(stroke
				(width 0.1)
				(type default)
			)
			(layer "F.Fab")
		)
		(fp_line
			(start 0.12065 -0.3048)
			(end 0.67945 -0.3048)
			(stroke
				(width 0.1)
				(type default)
			)
			(layer "F.Fab")
		)
		(fp_line
			(start 0.12065 -0.2794)
			(end 0.12065 -0.3048)
			(stroke
				(width 0.1)
				(type default)
			)
			(layer "F.Fab")
		)
		(fp_line
			(start 0.67945 -0.3048)
			(end 0.67945 0.3048)
			(stroke
				(width 0.1)
				(type default)
			)
			(layer "F.Fab")
		)
		(fp_line
			(start 0.67945 0.3048)
			(end 0.120396 0.3048)
			(stroke
				(width 0.1)
				(type default)
			)
			(layer "F.Fab")
		)
		(pad "1" smd circle
			(at -0.40005 0)
			(size 0 0)
			(layers "F.Cu" "F.Mask" "F.Paste")
			(net "P3V3_AUX")
		)
		(pad "2" smd circle
			(at 0.40005 0)
			(size 0 0)
			(layers "F.Cu" "F.Mask" "F.Paste")
			(net "SSD9_PEX_PWR_EN_R")
		)
	)
	(footprint ""
		(layer "F.Cu")
		(at 108.689902 -279.486868 -90)
		(property "Reference" "PC73"
			(at 0 0 270)
			(layer "F.SilkS")
			(hide yes)
			(effects
				(font
					(size 1.27 1.27)
				)
			)
		)
		(property "Value" ""
			(at 0 0 270)
			(layer "F.Fab")
			(effects
				(font
					(size 1.27 1.27)
				)
			)
		)
		(duplicate_pad_numbers_are_jumpers no)
		(fp_line
			(start -0.7874 0.4064)
			(end -0.7874 -0.4064)
			(stroke
				(width 0.1524)
				(type default)
			)
			(layer "F.SilkS")
		)
		(fp_line
			(start 0.7874 0.4064)
			(end -0.7874 0.4064)
			(stroke
				(width 0.1524)
				(type default)
			)
			(layer "F.SilkS")
		)
		(fp_line
			(start -0.7874 -0.4064)
			(end 0.7874 -0.4064)
			(stroke
				(width 0.1524)
				(type default)
			)
			(layer "F.SilkS")
		)
		(fp_line
			(start 0.7874 -0.4064)
			(end 0.7874 0.4064)
			(stroke
				(width 0.1524)
				(type default)
			)
			(layer "F.SilkS")
		)
		(fp_line
			(start -0.67945 0.3048)
			(end -0.67945 -0.305054)
			(stroke
				(width 0.1)
				(type default)
			)
			(layer "F.Fab")
		)
		(fp_line
			(start -0.12065 0.3048)
			(end -0.67945 0.3048)
			(stroke
				(width 0.1)
				(type default)
			)
			(layer "F.Fab")
		)
		(fp_line
			(start 0.120396 0.3048)
			(end 0.120396 0.2794)
			(stroke
				(width 0.1)
				(type default)
			)
			(layer "F.Fab")
		)
		(fp_line
			(start 0.67945 0.3048)
			(end 0.120396 0.3048)
			(stroke
				(width 0.1)
				(type default)
			)
			(layer "F.Fab")
		)
		(fp_line
			(start -0.12065 0.2794)
			(end -0.12065 0.3048)
			(stroke
				(width 0.1)
				(type default)
			)
			(layer "F.Fab")
		)
		(fp_line
			(start 0.120396 0.2794)
			(end -0.12065 0.2794)
			(stroke
				(width 0.1)
				(type default)
			)
			(layer "F.Fab")
		)
		(fp_line
			(start -0.12065 -0.2794)
			(end 0.12065 -0.2794)
			(stroke
				(width 0.1)
				(type default)
			)
			(layer "F.Fab")
		)
		(fp_line
			(start 0.12065 -0.2794)
			(end 0.12065 -0.3048)
			(stroke
				(width 0.1)
				(type default)
			)
			(layer "F.Fab")
		)
		(fp_line
			(start 0.12065 -0.3048)
			(end 0.67945 -0.3048)
			(stroke
				(width 0.1)
				(type default)
			)
			(layer "F.Fab")
		)
		(fp_line
			(start 0.67945 -0.3048)
			(end 0.67945 0.3048)
			(stroke
				(width 0.1)
				(type default)
			)
			(layer "F.Fab")
		)
		(fp_line
			(start -0.67945 -0.305054)
			(end -0.12065 -0.305054)
			(stroke
				(width 0.1)
				(type default)
			)
			(layer "F.Fab")
		)
		(fp_line
			(start -0.12065 -0.305054)
			(end -0.12065 -0.2794)
			(stroke
				(width 0.1)
				(type default)
			)
			(layer "F.Fab")
		)
		(pad "1" smd circle
			(at -0.40005 0 270)
			(size 0 0)
			(layers "F.Cu" "F.Mask" "F.Paste")
			(net "P0V8_PEX0_VREF")
		)
		(pad "2" smd circle
			(at 0.40005 0 270)
			(size 0 0)
			(layers "F.Cu" "F.Mask" "F.Paste")
			(net "GND")
		)
	)
	(footprint ""
		(layer "F.Cu")
		(at 270.616426 -200.80859)
		(property "Reference" "ME7"
			(at 0.1016 -12.690348 0)
			(unlocked yes)
			(layer "F.SilkS")
			(effects
				(font
					(size 0.7874 0.5842)
					(thickness 0.1524)
				)
				(justify left)
			)
		)
		(property "Value" ""
			(at 0 0 0)
			(layer "F.Fab")
			(effects
				(font
					(size 1.27 1.27)
				)
			)
		)
		(duplicate_pad_numbers_are_jumpers no)
		(fp_line
			(start 0 -11.999976)
			(end 0 -10.475976)
			(stroke
				(width 0.1524)
				(type default)
			)
			(layer "F.SilkS")
		)
		(fp_line
			(start 0 -1.524)
			(end 0 0)
			(stroke
				(width 0.1524)
				(type default)
			)
			(layer "F.SilkS")
		)
		(fp_line
			(start 0 0)
			(end 1.524 0)
			(stroke
				(width 0.1524)
				(type default)
			)
			(layer "F.SilkS")
		)
		(fp_line
			(start 1.524 -11.999976)
			(end 0 -11.999976)
			(stroke
				(width 0.1524)
				(type default)
			)
			(layer "F.SilkS")
		)
		(fp_line
			(start 15.475966 0)
			(end 16.999966 0)
			(stroke
				(width 0.1524)
				(type default)
			)
			(layer "F.SilkS")
		)
		(fp_line
			(start 16.999966 -11.999976)
			(end 15.475966 -11.999976)
			(stroke
				(width 0.1524)
				(type default)
			)
			(layer "F.SilkS")
		)
		(fp_line
			(start 16.999966 -10.475976)
			(end 16.999966 -11.999976)
			(stroke
				(width 0.1524)
				(type default)
			)
			(layer "F.SilkS")
		)
		(fp_line
			(start 16.999966 0)
			(end 16.999966 -1.524)
			(stroke
				(width 0.1524)
				(type default)
			)
			(layer "F.SilkS")
		)
		(fp_text user "MAC"
			(at 0.3302 -10.50925 0)
			(unlocked yes)
			(layer "F.SilkS")
			(effects
				(font
					(size 1.905 1.4224)
					(thickness 0.1524)
				)
				(justify left)
			)
		)
	)
	(footprint ""
		(layer "F.Cu")
		(at 340.561422 -194.48145 180)
		(property "Reference" "R4240"
			(at 0 0 180)
			(layer "F.SilkS")
			(hide yes)
			(effects
				(font
					(size 1.27 1.27)
				)
			)
		)
		(property "Value" ""
			(at 0 0 180)
			(layer "F.Fab")
			(effects
				(font
					(size 1.27 1.27)
				)
			)
		)
		(duplicate_pad_numbers_are_jumpers no)
		(fp_line
			(start 0.7874 0.4064)
			(end -0.7874 0.4064)
			(stroke
				(width 0.1524)
				(type default)
			)
			(layer "F.SilkS")
		)
		(fp_line
			(start 0.7874 -0.4064)
			(end 0.7874 0.4064)
			(stroke
				(width 0.1524)
				(type default)
			)
			(layer "F.SilkS")
		)
		(fp_line
			(start -0.7874 0.4064)
			(end -0.7874 -0.4064)
			(stroke
				(width 0.1524)
				(type default)
			)
			(layer "F.SilkS")
		)
		(fp_line
			(start -0.7874 -0.4064)
			(end 0.7874 -0.4064)
			(stroke
				(width 0.1524)
				(type default)
			)
			(layer "F.SilkS")
		)
		(fp_line
			(start 0.67945 0.3048)
			(end 0.120396 0.3048)
			(stroke
				(width 0.1)
				(type default)
			)
			(layer "F.Fab")
		)
		(fp_line
			(start 0.67945 -0.3048)
			(end 0.67945 0.3048)
			(stroke
				(width 0.1)
				(type default)
			)
			(layer "F.Fab")
		)
		(fp_line
			(start 0.12065 -0.2794)
			(end 0.12065 -0.3048)
			(stroke
				(width 0.1)
				(type default)
			)
			(layer "F.Fab")
		)
		(fp_line
			(start 0.12065 -0.3048)
			(end 0.67945 -0.3048)
			(stroke
				(width 0.1)
				(type default)
			)
			(layer "F.Fab")
		)
		(fp_line
			(start 0.120396 0.3048)
			(end 0.120396 0.2794)
			(stroke
				(width 0.1)
				(type default)
			)
			(layer "F.Fab")
		)
		(fp_line
			(start 0.120396 0.2794)
			(end -0.12065 0.2794)
			(stroke
				(width 0.1)
				(type default)
			)
			(layer "F.Fab")
		)
		(fp_line
			(start -0.12065 0.3048)
			(end -0.67945 0.3048)
			(stroke
				(width 0.1)
				(type default)
			)
			(layer "F.Fab")
		)
		(fp_line
			(start -0.12065 0.2794)
			(end -0.12065 0.3048)
			(stroke
				(width 0.1)
				(type default)
			)
			(layer "F.Fab")
		)
		(fp_line
			(start -0.12065 -0.2794)
			(end 0.12065 -0.2794)
			(stroke
				(width 0.1)
				(type default)
			)
			(layer "F.Fab")
		)
		(fp_line
			(start -0.12065 -0.305054)
			(end -0.12065 -0.2794)
			(stroke
				(width 0.1)
				(type default)
			)
			(layer "F.Fab")
		)
		(fp_line
			(start -0.67945 0.3048)
			(end -0.67945 -0.305054)
			(stroke
				(width 0.1)
				(type default)
			)
			(layer "F.Fab")
		)
		(fp_line
			(start -0.67945 -0.305054)
			(end -0.12065 -0.305054)
			(stroke
				(width 0.1)
				(type default)
			)
			(layer "F.Fab")
		)
		(pad "1" smd circle
			(at -0.40005 0 180)
			(size 0 0)
			(layers "F.Cu" "F.Mask" "F.Paste")
			(net "P3V3_AUX")
		)
		(pad "2" smd circle
			(at 0.40005 0 180)
			(size 0 0)
			(layers "F.Cu" "F.Mask" "F.Paste")
			(net "FM_SOL_UART_CH_SEL")
		)
	)
	(footprint ""
		(layer "F.Cu")
		(at 431.694082 -29.507688 -90)
		(property "Reference" "PC976"
			(at 0 0 270)
			(layer "F.SilkS")
			(hide yes)
			(effects
				(font
					(size 1.27 1.27)
				)
			)
		)
		(property "Value" ""
			(at 0 0 270)
			(layer "F.Fab")
			(effects
				(font
					(size 1.27 1.27)
				)
			)
		)
		(duplicate_pad_numbers_are_jumpers no)
		(fp_line
			(start -1.524 0.762)
			(end -1.524 -0.762)
			(stroke
				(width 0.1524)
				(type default)
			)
			(layer "F.SilkS")
		)
		(fp_line
			(start 1.524 0.762)
			(end -1.524 0.762)
			(stroke
				(width 0.1524)
				(type default)
			)
			(layer "F.SilkS")
		)
		(fp_line
			(start -1.524 -0.762)
			(end 1.524 -0.762)
			(stroke
				(width 0.1524)
				(type default)
			)
			(layer "F.SilkS")
		)
		(fp_line
			(start 1.524 -0.762)
			(end 1.524 0.762)
			(stroke
				(width 0.1524)
				(type default)
			)
			(layer "F.SilkS")
		)
		(fp_line
			(start -1.1049 0.724916)
			(end 1.1049 0.724916)
			(stroke
				(width 0.1)
				(type default)
			)
			(layer "F.Fab")
		)
		(fp_line
			(start 1.1049 0.724916)
			(end 1.1049 -0.724916)
			(stroke
				(width 0.1)
				(type default)
			)
			(layer "F.Fab")
		)
		(fp_line
			(start -1.1049 -0.724916)
			(end -1.1049 0.724916)
			(stroke
				(width 0.1)
				(type default)
			)
			(layer "F.Fab")
		)
		(fp_line
			(start 1.1049 -0.724916)
			(end -1.1049 -0.724916)
			(stroke
				(width 0.1)
				(type default)
			)
			(layer "F.Fab")
		)
		(pad "1" smd rect
			(at -0.889 0 90)
			(size 1.016 1.27)
			(layers "F.Cu" "F.Mask" "F.Paste")
			(net "P3V3_SSD15")
		)
		(pad "2" smd rect
			(at 0.889 0 90)
			(size 1.016 1.27)
			(layers "F.Cu" "F.Mask" "F.Paste")
			(net "GND")
		)
	)
	(footprint ""
		(layer "F.Cu")
		(at 234.855512 -234.728004 -90)
		(property "Reference" "R6190"
			(at 0 0 270)
			(layer "F.SilkS")
			(hide yes)
			(effects
				(font
					(size 1.27 1.27)
				)
			)
		)
		(property "Value" ""
			(at 0 0 270)
			(layer "F.Fab")
			(effects
				(font
					(size 1.27 1.27)
				)
			)
		)
		(duplicate_pad_numbers_are_jumpers no)
		(fp_line
			(start -0.7874 0.4064)
			(end -0.7874 -0.4064)
			(stroke
				(width 0.1524)
				(type default)
			)
			(layer "F.SilkS")
		)
		(fp_line
			(start 0.7874 0.4064)
			(end -0.7874 0.4064)
			(stroke
				(width 0.1524)
				(type default)
			)
			(layer "F.SilkS")
		)
		(fp_line
			(start -0.7874 -0.4064)
			(end 0.7874 -0.4064)
			(stroke
				(width 0.1524)
				(type default)
			)
			(layer "F.SilkS")
		)
		(fp_line
			(start 0.7874 -0.4064)
			(end 0.7874 0.4064)
			(stroke
				(width 0.1524)
				(type default)
			)
			(layer "F.SilkS")
		)
		(fp_line
			(start -0.67945 0.3048)
			(end -0.67945 -0.305054)
			(stroke
				(width 0.1)
				(type default)
			)
			(layer "F.Fab")
		)
		(fp_line
			(start -0.12065 0.3048)
			(end -0.67945 0.3048)
			(stroke
				(width 0.1)
				(type default)
			)
			(layer "F.Fab")
		)
		(fp_line
			(start 0.120396 0.3048)
			(end 0.120396 0.2794)
			(stroke
				(width 0.1)
				(type default)
			)
			(layer "F.Fab")
		)
		(fp_line
			(start 0.67945 0.3048)
			(end 0.120396 0.3048)
			(stroke
				(width 0.1)
				(type default)
			)
			(layer "F.Fab")
		)
		(fp_line
			(start -0.12065 0.2794)
			(end -0.12065 0.3048)
			(stroke
				(width 0.1)
				(type default)
			)
			(layer "F.Fab")
		)
		(fp_line
			(start 0.120396 0.2794)
			(end -0.12065 0.2794)
			(stroke
				(width 0.1)
				(type default)
			)
			(layer "F.Fab")
		)
		(fp_line
			(start -0.12065 -0.2794)
			(end 0.12065 -0.2794)
			(stroke
				(width 0.1)
				(type default)
			)
			(layer "F.Fab")
		)
		(fp_line
			(start 0.12065 -0.2794)
			(end 0.12065 -0.3048)
			(stroke
				(width 0.1)
				(type default)
			)
			(layer "F.Fab")
		)
		(fp_line
			(start 0.12065 -0.3048)
			(end 0.67945 -0.3048)
			(stroke
				(width 0.1)
				(type default)
			)
			(layer "F.Fab")
		)
		(fp_line
			(start 0.67945 -0.3048)
			(end 0.67945 0.3048)
			(stroke
				(width 0.1)
				(type default)
			)
			(layer "F.Fab")
		)
		(fp_line
			(start -0.67945 -0.305054)
			(end -0.12065 -0.305054)
			(stroke
				(width 0.1)
				(type default)
			)
			(layer "F.Fab")
		)
		(fp_line
			(start -0.12065 -0.305054)
			(end -0.12065 -0.2794)
			(stroke
				(width 0.1)
				(type default)
			)
			(layer "F.Fab")
		)
		(pad "1" smd circle
			(at -0.40005 0 270)
			(size 0 0)
			(layers "F.Cu" "F.Mask" "F.Paste")
			(net "GND")
		)
		(pad "2" smd circle
			(at 0.40005 0 270)
			(size 0 0)
			(layers "F.Cu" "F.Mask" "F.Paste")
			(net "SSD8_PWRDIS_BIC_R")
		)
	)
)
